(kicad_pcb
	(version 20241229)
	(generator "pcbnew")
	(generator_version "9.0")
	(general
		(thickness 1.61)
		(legacy_teardrops no)
	)
	(paper "A3")
	(title_block
		(title "RDIMM DDR5 Tester")
		(date "2026-05-21")
		(rev "2.2.0")
		(company "Antmicro")
		(comment 9 "footprints 722-725 of 796")
	)
	(layers
		(0 "F.Cu" signal)
		(4 "In1.Cu" power)
		(6 "In2.Cu" mixed)
		(8 "In3.Cu" power)
		(10 "In4.Cu" mixed)
		(12 "In5.Cu" power)
		(14 "In6.Cu" mixed)
		(16 "In7.Cu" power)
		(18 "In8.Cu" power)
		(20 "In9.Cu" mixed)
		(22 "In10.Cu" power)
		(2 "B.Cu" signal)
		(9 "F.Adhes" user "F.Adhesive")
		(11 "B.Adhes" user "B.Adhesive")
		(13 "F.Paste" user)
		(15 "B.Paste" user)
		(5 "F.SilkS" user "F.Silkscreen")
		(7 "B.SilkS" user "B.Silkscreen")
		(1 "F.Mask" user)
		(3 "B.Mask" user)
		(17 "Dwgs.User" user "User.Drawings")
		(19 "Cmts.User" user "User.Comments")
		(21 "Eco1.User" user "User.Eco1")
		(23 "Eco2.User" user "User.Eco2")
		(25 "Edge.Cuts" user)
		(27 "Margin" user)
		(31 "F.CrtYd" user "F.Courtyard")
		(29 "B.CrtYd" user "B.Courtyard")
		(35 "F.Fab" user)
		(33 "B.Fab" user)
	)
	(footprint "antmicro-footprints:C_0402_1005Metric_EIA"
		(layer "B.Cu")
		(at 194.499999 159)
		(descr "Capacitor SMD 0402 (1005 Metric), square (rectangular) end terminal, IPC_7351 nominal, (Body size source: IPC-SM-782 page 76, https://www.pcb-3d.com/wordpress/wp-content/uploads/ipc-sm-782a_amendment_1_and_2.pdf)")
		(tags "capacitor 0402")
		(property "Reference" "C99"
			(at -32.149999 -10.3 0)
			(layer "B.SilkS")
			(effects
				(font
					(size 0.7 0.7)
					(thickness 0.15)
				)
				(justify right bottom mirror)
			)
		)
		(property "Value" "C_100n_0402"
			(at 0 -1.169 0)
			(layer "B.Fab")
			(effects
				(font
					(size 0.7 0.7)
					(thickness 0.15)
				)
				(justify right bottom mirror)
			)
		)
		(property "Datasheet" "https://www.murata.com/products/productdetail?partno=GRM155R61H104KE14%23"
			(at 0 0 0)
			(layer "F.Fab")
			(hide yes)
			(effects
				(font
					(size 1.27 1.27)
					(thickness 0.15)
				)
			)
		)
		(property "MPN" "GRM155R61H104KE14D"
			(at 0 0 0)
			(unlocked yes)
			(layer "B.Fab")
			(hide yes)
			(effects
				(font
					(size 1 1)
					(thickness 0.15)
				)
				(justify mirror)
			)
		)
		(property "Manufacturer" "Murata"
			(at 0 0 0)
			(unlocked yes)
			(layer "B.Fab")
			(hide yes)
			(effects
				(font
					(size 1 1)
					(thickness 0.15)
				)
				(justify mirror)
			)
		)
		(property "License" "Apache-2.0"
			(at 0 0 0)
			(unlocked yes)
			(layer "B.Fab")
			(hide yes)
			(effects
				(font
					(size 1 1)
					(thickness 0.15)
				)
				(justify mirror)
			)
		)
		(property "Author" "Antmicro"
			(at 0 0 0)
			(unlocked yes)
			(layer "B.Fab")
			(hide yes)
			(effects
				(font
					(size 1 1)
					(thickness 0.15)
				)
				(justify mirror)
			)
		)
		(property "Val" "100n"
			(at 0 0 0)
			(unlocked yes)
			(layer "B.Fab")
			(hide yes)
			(effects
				(font
					(size 1 1)
					(thickness 0.15)
				)
				(justify mirror)
			)
		)
		(property "Voltage" "50V"
			(at 0 0 0)
			(unlocked yes)
			(layer "B.Fab")
			(hide yes)
			(effects
				(font
					(size 1 1)
					(thickness 0.15)
				)
				(justify mirror)
			)
		)
		(property "Dielectric" "X5R"
			(at 0 0 0)
			(unlocked yes)
			(layer "B.Fab")
			(hide yes)
			(effects
				(font
					(size 1 1)
					(thickness 0.15)
				)
				(justify mirror)
			)
		)
		(sheetname "/FPGA power/")
		(sheetfile "fpga-power.kicad_sch")
		(attr smd)
		(fp_rect
			(start -0.95 0.45)
			(end 0.95 -0.45)
			(stroke
				(width 0.05)
				(type default)
			)
			(fill no)
			(layer "B.CrtYd")
		)
		(fp_line
			(start -0.5 -0.248)
			(end -0.5 0.25)
			(stroke
				(width 0.15)
				(type solid)
			)
			(layer "B.Fab")
		)
		(fp_line
			(start -0.5 0.25)
			(end 0.498 0.25)
			(stroke
				(width 0.15)
				(type solid)
			)
			(layer "B.Fab")
		)
		(fp_line
			(start 0.498 -0.248)
			(end -0.5 -0.248)
			(stroke
				(width 0.15)
				(type solid)
			)
			(layer "B.Fab")
		)
		(fp_line
			(start 0.498 0.25)
			(end 0.498 -0.248)
			(stroke
				(width 0.15)
				(type solid)
			)
			(layer "B.Fab")
		)
		(fp_text user "License: Apache-2.0"
			(at -0.9656 -4.369 180)
			(layer "B.Fab")
			(effects
				(font
					(size 0.7 0.7)
					(thickness 0.15)
				)
				(justify left bottom mirror)
			)
		)
		(fp_text user "${REFERENCE}"
			(at -0.9656 -3.169 180)
			(layer "B.Fab")
			(effects
				(font
					(size 0.7 0.7)
					(thickness 0.15)
				)
				(justify left bottom mirror)
			)
		)
		(fp_text user "Author: Antmicro"
			(at -0.9656 -5.569 180)
			(layer "B.Fab")
			(effects
				(font
					(size 0.7 0.7)
					(thickness 0.15)
				)
				(justify left bottom mirror)
			)
		)
		(pad "1" smd roundrect
			(at -0.5 0 270)
			(size 0.6 0.6)
			(layers "B.Cu" "B.Mask" "B.Paste")
			(roundrect_rratio 0.25)
			(net 1 "GND")
			(pintype "passive")
		)
		(pad "2" smd roundrect
			(at 0.498 0)
			(size 0.6 0.6)
			(layers "B.Cu" "B.Mask" "B.Paste")
			(roundrect_rratio 0.25)
			(net 820 "+0V9_MGTAVCC")
			(pintype "passive")
		)
	)
	(footprint "antmicro-footprints:USON-10_2.5x1mm_P0.5mm"
		(layer "B.Cu")
		(at 107.804 160.119 180)
		(descr "USON-10 2.5x1mm_ Pitch 0.5mm")
		(tags "USON-10 2.5x1mm Pitch 0.5mm")
		(property "Reference" "U41"
			(at -1.946 -0.731 90)
			(layer "B.SilkS")
			(effects
				(font
					(size 0.7 0.7)
					(thickness 0.15)
				)
				(justify right bottom mirror)
			)
		)
		(property "Value" "TPD4E05U06QDQARQ1"
			(at 0.018 -2.499 0)
			(layer "B.Fab")
			(effects
				(font
					(size 0.7 0.7)
					(thickness 0.15)
				)
				(justify left bottom mirror)
			)
		)
		(property "Datasheet" "https://www.ti.com/lit/ds/symlink/tpd4e05u06-q1.pdf?HQS=dis-mous-null-mousermode-dsf-pf-null-wwe&ts=1663591265741&ref_url=https%253A%252F%252Fwww.mouser.com%252F"
			(at 0 0 180)
			(layer "F.Fab")
			(hide yes)
			(effects
				(font
					(size 1.27 1.27)
					(thickness 0.15)
				)
			)
		)
		(property "Manufacturer" "Texas Instruments"
			(at 0 0 180)
			(unlocked yes)
			(layer "B.Fab")
			(hide yes)
			(effects
				(font
					(size 1 1)
					(thickness 0.15)
				)
				(justify mirror)
			)
		)
		(property "MPN" "TPD4E05U06QDQARQ1"
			(at 0 0 180)
			(unlocked yes)
			(layer "B.Fab")
			(hide yes)
			(effects
				(font
					(size 1 1)
					(thickness 0.15)
				)
				(justify mirror)
			)
		)
		(property "Author" "Antmicro"
			(at 0 0 180)
			(unlocked yes)
			(layer "B.Fab")
			(hide yes)
			(effects
				(font
					(size 1 1)
					(thickness 0.15)
				)
				(justify mirror)
			)
		)
		(property "License" "Apache-2.0"
			(at 0 0 180)
			(unlocked yes)
			(layer "B.Fab")
			(hide yes)
			(effects
				(font
					(size 1 1)
					(thickness 0.15)
				)
				(justify mirror)
			)
		)
		(sheetname "/HDMI + SD Card/")
		(sheetfile "hdmi-sd-card.kicad_sch")
		(attr smd)
		(fp_line
			(start 0.498 1.401)
			(end -0.5 1.401)
			(stroke
				(width 0.15)
				(type solid)
			)
			(layer "B.SilkS")
		)
		(fp_line
			(start 0.498 -1.398)
			(end -0.5 -1.398)
			(stroke
				(width 0.15)
				(type solid)
			)
			(layer "B.SilkS")
		)
		(fp_circle
			(center -0.68 1.27)
			(end -0.63 1.27)
			(stroke
				(width 0.15)
				(type solid)
			)
			(fill yes)
			(layer "B.SilkS")
		)
		(fp_rect
			(start -0.8 1.5)
			(end 0.8 -1.499)
			(stroke
				(width 0.05)
				(type solid)
			)
			(fill no)
			(layer "B.CrtYd")
		)
		(fp_line
			(start 0.498 1.25)
			(end 0.498 -1.249)
			(stroke
				(width 0.15)
				(type solid)
			)
			(layer "B.Fab")
		)
		(fp_line
			(start 0.498 1.25)
			(end -0.25 1.25)
			(stroke
				(width 0.15)
				(type solid)
			)
			(layer "B.Fab")
		)
		(fp_line
			(start -0.25 1.25)
			(end -0.5 1)
			(stroke
				(width 0.15)
				(type solid)
			)
			(layer "B.Fab")
		)
		(fp_line
			(start -0.5 1)
			(end -0.5 -1.249)
			(stroke
				(width 0.15)
				(type solid)
			)
			(layer "B.Fab")
		)
		(fp_line
			(start -0.5 -1.249)
			(end 0.498 -1.249)
			(stroke
				(width 0.15)
				(type solid)
			)
			(layer "B.Fab")
		)
		(fp_text user "Author: Antmicro"
			(at -0.802 -5.7 0)
			(layer "B.Fab")
			(effects
				(font
					(size 0.7 0.7)
					(thickness 0.15)
				)
				(justify left bottom mirror)
			)
		)
		(fp_text user "License: Apache-2.0"
			(at -0.802 -6.9 0)
			(layer "B.Fab")
			(effects
				(font
					(size 0.7 0.7)
					(thickness 0.15)
				)
				(justify left bottom mirror)
			)
		)
		(fp_text user "${REFERENCE}"
			(at -0.802 -4.498 0)
			(layer "B.Fab")
			(effects
				(font
					(size 0.7 0.7)
					(thickness 0.15)
				)
				(justify left bottom mirror)
			)
		)
		(pad "1" smd roundrect
			(at -0.387 1 270)
			(size 0.25 0.55)
			(layers "B.Cu" "B.Mask" "B.Paste")
			(roundrect_rratio 0.25)
			(net 380 "/FPGA MGT Interface/HDMI_IN.D0_P")
			(pintype "passive")
		)
		(pad "2" smd roundrect
			(at -0.387 0.5 270)
			(size 0.25 0.55)
			(layers "B.Cu" "B.Mask" "B.Paste")
			(roundrect_rratio 0.25)
			(net 349 "/FPGA MGT Interface/HDMI_IN.D0_N")
			(pintype "passive")
		)
		(pad "3" smd roundrect
			(at -0.387 0 270)
			(size 0.4 0.55)
			(layers "B.Cu" "B.Mask" "B.Paste")
			(roundrect_rratio 0.25)
			(net 1 "GND")
			(pintype "power_in")
		)
		(pad "4" smd roundrect
			(at -0.387 -0.498 270)
			(size 0.25 0.55)
			(layers "B.Cu" "B.Mask" "B.Paste")
			(roundrect_rratio 0.25)
			(net 269 "/FPGA MGT Interface/HDMI_IN.CLK_P")
			(pintype "passive")
		)
		(pad "5" smd roundrect
			(at -0.387 -0.998 270)
			(size 0.25 0.55)
			(layers "B.Cu" "B.Mask" "B.Paste")
			(roundrect_rratio 0.25)
			(net 292 "/FPGA MGT Interface/HDMI_IN.CLK_N")
			(pintype "passive")
		)
		(pad "6" smd roundrect
			(at 0.385 -0.998 270)
			(size 0.25 0.55)
			(layers "B.Cu" "B.Mask" "B.Paste")
			(roundrect_rratio 0.25)
			(net 292 "/FPGA MGT Interface/HDMI_IN.CLK_N")
			(pintype "passive")
		)
		(pad "7" smd roundrect
			(at 0.385 -0.498 270)
			(size 0.25 0.55)
			(layers "B.Cu" "B.Mask" "B.Paste")
			(roundrect_rratio 0.25)
			(net 269 "/FPGA MGT Interface/HDMI_IN.CLK_P")
			(pintype "passive")
		)
		(pad "8" smd roundrect
			(at 0.385 0 270)
			(size 0.4 0.55)
			(layers "B.Cu" "B.Mask" "B.Paste")
			(roundrect_rratio 0.25)
			(net 1 "GND")
			(pintype "passive")
		)
		(pad "9" smd roundrect
			(at 0.385 0.5 270)
			(size 0.25 0.55)
			(layers "B.Cu" "B.Mask" "B.Paste")
			(roundrect_rratio 0.25)
			(net 349 "/FPGA MGT Interface/HDMI_IN.D0_N")
			(pintype "passive")
		)
		(pad "10" smd roundrect
			(at 0.385 1 270)
			(size 0.25 0.55)
			(layers "B.Cu" "B.Mask" "B.Paste")
			(roundrect_rratio 0.25)
			(net 380 "/FPGA MGT Interface/HDMI_IN.D0_P")
			(pintype "passive")
		)
	)
	(footprint "antmicro-footprints:R_0402_1005Metric"
		(layer "B.Cu")
		(at 225.32 182.765 180)
		(descr "Resistor SMD 0402")
		(tags "resistor SMD 0402")
		(property "Reference" "R185"
			(at -4.68 -0.535 0)
			(layer "B.SilkS")
			(effects
				(font
					(size 0.7 0.7)
					(thickness 0.15)
				)
				(justify left bottom mirror)
			)
		)
		(property "Value" "R_0R_0402"
			(at -1.011843 -1.772047 0)
			(layer "B.Fab")
			(effects
				(font
					(size 0.7 0.7)
					(thickness 0.15)
				)
				(justify left bottom mirror)
			)
		)
		(property "Datasheet" "https://industrial.panasonic.com/cdbs/www-data/pdf/RDA0000/AOA0000C301.pdf"
			(at 0 0 180)
			(layer "F.Fab")
			(hide yes)
			(effects
				(font
					(size 1.27 1.27)
					(thickness 0.15)
				)
			)
		)
		(property "MPN" "ERJ2GE0R00X"
			(at 0 0 180)
			(unlocked yes)
			(layer "B.Fab")
			(hide yes)
			(effects
				(font
					(size 1 1)
					(thickness 0.15)
				)
				(justify mirror)
			)
		)
		(property "Manufacturer" "Panasonic"
			(at 0 0 180)
			(unlocked yes)
			(layer "B.Fab")
			(hide yes)
			(effects
				(font
					(size 1 1)
					(thickness 0.15)
				)
				(justify mirror)
			)
		)
		(property "License" "Apache-2.0"
			(at 0 0 180)
			(unlocked yes)
			(layer "B.Fab")
			(hide yes)
			(effects
				(font
					(size 1 1)
					(thickness 0.15)
				)
				(justify mirror)
			)
		)
		(property "Author" "Antmicro"
			(at 0 0 180)
			(unlocked yes)
			(layer "B.Fab")
			(hide yes)
			(effects
				(font
					(size 1 1)
					(thickness 0.15)
				)
				(justify mirror)
			)
		)
		(property "Val" "0R"
			(at 0 0 180)
			(unlocked yes)
			(layer "B.Fab")
			(hide yes)
			(effects
				(font
					(size 1 1)
					(thickness 0.15)
				)
				(justify mirror)
			)
		)
		(property "Tolerance" "~"
			(at 0 0 180)
			(unlocked yes)
			(layer "B.Fab")
			(hide yes)
			(effects
				(font
					(size 1 1)
					(thickness 0.15)
				)
				(justify mirror)
			)
		)
		(property "Current" "1A"
			(at 0 0 180)
			(unlocked yes)
			(layer "B.Fab")
			(hide yes)
			(effects
				(font
					(size 1 1)
					(thickness 0.15)
				)
				(justify mirror)
			)
		)
		(sheetname "/Supply/DC-DC VCCINT/")
		(sheetfile "dc-dc-vccint.kicad_sch")
		(attr smd)
		(fp_rect
			(start -0.925 0.47)
			(end 0.925 -0.47)
			(stroke
				(width 0.05)
				(type default)
			)
			(fill no)
			(layer "B.CrtYd")
		)
		(fp_rect
			(start -0.5 0.25)
			(end 0.5 -0.25)
			(stroke
				(width 0.15)
				(type solid)
			)
			(fill no)
			(layer "B.Fab")
		)
		(fp_text user "License: Apache-2.0"
			(at -0.95 -5.169 0)
			(layer "B.Fab")
			(effects
				(font
					(size 0.7 0.7)
					(thickness 0.15)
				)
				(justify left bottom mirror)
			)
		)
		(fp_text user "Author: Antmicro"
			(at -0.95 -4.169 0)
			(layer "B.Fab")
			(effects
				(font
					(size 0.7 0.7)
					(thickness 0.15)
				)
				(justify left bottom mirror)
			)
		)
		(fp_text user "${REFERENCE}"
			(at -0.95 -3.168 0)
			(layer "B.Fab")
			(effects
				(font
					(size 0.7 0.7)
					(thickness 0.15)
				)
				(justify left bottom mirror)
			)
		)
		(pad "1" smd roundrect
			(at -0.48 0 180)
			(size 0.59 0.64)
			(layers "B.Cu" "B.Mask" "B.Paste")
			(roundrect_rratio 0.25)
			(net 723 "/Supply/DC-DC VCCINT/PASS1")
			(pintype "passive")
		)
		(pad "2" smd roundrect
			(at 0.48 0 180)
			(size 0.59 0.64)
			(layers "B.Cu" "B.Mask" "B.Paste")
			(roundrect_rratio 0.25)
			(net 724 "/Supply/DC-DC VCCINT/TAKE0")
			(pintype "passive")
		)
	)
	(footprint "antmicro-footprints:SC70-3"
		(layer "B.Cu")
		(at 114.27 163.97)
		(property "Reference" "Q21"
			(at -1.37 -1.42 0)
			(layer "B.SilkS")
			(effects
				(font
					(size 0.7 0.7)
					(thickness 0.15)
				)
				(justify right bottom mirror)
			)
		)
		(property "Value" "BSS138PW"
			(at 0 -2.3 0)
			(layer "B.Fab")
			(effects
				(font
					(size 0.7 0.7)
					(thickness 0.15)
				)
				(justify right bottom mirror)
			)
		)
		(property "Datasheet" "https://assets.nexperia.com/documents/data-sheet/BSS138PW.pdf"
			(at 0 0 0)
			(layer "F.Fab")
			(hide yes)
			(effects
				(font
					(size 1.27 1.27)
					(thickness 0.15)
				)
			)
		)
		(property "MPN" "BSS138PW"
			(at 0 0 0)
			(unlocked yes)
			(layer "B.Fab")
			(hide yes)
			(effects
				(font
					(size 1 1)
					(thickness 0.15)
				)
				(justify mirror)
			)
		)
		(property "Manufacturer" "Nexperia"
			(at 0 0 0)
			(unlocked yes)
			(layer "B.Fab")
			(hide yes)
			(effects
				(font
					(size 1 1)
					(thickness 0.15)
				)
				(justify mirror)
			)
		)
		(property "Author" "Antmicro"
			(at 0 0 0)
			(unlocked yes)
			(layer "B.Fab")
			(hide yes)
			(effects
				(font
					(size 1 1)
					(thickness 0.15)
				)
				(justify mirror)
			)
		)
		(property "License" "Apache-2.0"
			(at 0 0 0)
			(unlocked yes)
			(layer "B.Fab")
			(hide yes)
			(effects
				(font
					(size 1 1)
					(thickness 0.15)
				)
				(justify mirror)
			)
		)
		(sheetname "/HDMI + SD Card/")
		(sheetfile "hdmi-sd-card.kicad_sch")
		(attr smd)
		(fp_line
			(start -0.3 -1)
			(end 0.627 -1.001)
			(stroke
				(width 0.15)
				(type solid)
			)
			(layer "B.SilkS")
		)
		(fp_line
			(start -0.3 1)
			(end 0.627 0.999)
			(stroke
				(width 0.15)
				(type solid)
			)
			(layer "B.SilkS")
		)
		(fp_line
			(start 0.627 -0.6)
			(end 0.627 -1.001)
			(stroke
				(width 0.15)
				(type solid)
			)
			(layer "B.SilkS")
		)
		(fp_line
			(start 0.627 0.6)
			(end 0.627 0.999)
			(stroke
				(width 0.15)
				(type solid)
			)
			(layer "B.SilkS")
		)
		(fp_line
			(start -1.4 -1)
			(end -1.4 1)
			(stroke
				(width 0.05)
				(type solid)
			)
			(layer "B.CrtYd")
		)
		(fp_line
			(start -0.9 -1.3)
			(end -0.9 -1)
			(stroke
				(width 0.05)
				(type solid)
			)
			(layer "B.CrtYd")
		)
		(fp_line
			(start -0.9 -1)
			(end -1.4 -1)
			(stroke
				(width 0.05)
				(type solid)
			)
			(layer "B.CrtYd")
		)
		(fp_line
			(start -0.9 1)
			(end -1.4 1)
			(stroke
				(width 0.05)
				(type solid)
			)
			(layer "B.CrtYd")
		)
		(fp_line
			(start -0.9 1.3)
			(end -0.9 1)
			(stroke
				(width 0.05)
				(type solid)
			)
			(layer "B.CrtYd")
		)
		(fp_line
			(start -0.9 1.3)
			(end 0.9 1.3)
			(stroke
				(width 0.05)
				(type solid)
			)
			(layer "B.CrtYd")
		)
		(fp_line
			(start 0.9 -1.3)
			(end -0.9 -1.3)
			(stroke
				(width 0.05)
				(type solid)
			)
			(layer "B.CrtYd")
		)
		(fp_line
			(start 0.9 -0.4)
			(end 0.9 -1.3)
			(stroke
				(width 0.05)
				(type solid)
			)
			(layer "B.CrtYd")
		)
		(fp_line
			(start 0.9 0.4)
			(end 1.4 0.4)
			(stroke
				(width 0.05)
				(type solid)
			)
			(layer "B.CrtYd")
		)
		(fp_line
			(start 0.9 1.3)
			(end 0.9 0.4)
			(stroke
				(width 0.05)
				(type solid)
			)
			(layer "B.CrtYd")
		)
		(fp_line
			(start 1.4 -0.4)
			(end 0.9 -0.4)
			(stroke
				(width 0.05)
				(type solid)
			)
			(layer "B.CrtYd")
		)
		(fp_line
			(start 1.4 0.4)
			(end 1.4 -0.4)
			(stroke
				(width 0.05)
				(type solid)
			)
			(layer "B.CrtYd")
		)
		(fp_rect
			(start -0.623 0.999)
			(end 0.627 -1.001)
			(stroke
				(width 0.15)
				(type solid)
			)
			(fill no)
			(layer "B.Fab")
		)
		(fp_text user "License: Apache-2.0"
			(at -1.45 -6.782 180)
			(layer "B.Fab")
			(effects
				(font
					(size 0.7 0.7)
					(thickness 0.15)
				)
				(justify left bottom mirror)
			)
		)
		(fp_text user "${REFERENCE}"
			(at -1.45 -4.783 180)
			(layer "B.Fab")
			(effects
				(font
					(size 0.7 0.7)
					(thickness 0.15)
				)
				(justify left bottom mirror)
			)
		)
		(fp_text user "Author: Antmicro"
			(at -1.45 -5.782 180)
			(layer "B.Fab")
			(effects
				(font
					(size 0.7 0.7)
					(thickness 0.15)
				)
				(justify left bottom mirror)
			)
		)
		(pad "1" smd rect
			(at -1.051 0.65 270)
			(size 0.6 0.6)
			(layers "B.Cu" "B.Mask" "B.Paste")
			(net 297 "/HDMI + SD Card/HDMI_IN_5V")
			(pinfunction "G")
			(pintype "passive")
		)
		(pad "2" smd rect
			(at -1.051 -0.65 270)
			(size 0.6 0.6)
			(layers "B.Cu" "B.Mask" "B.Paste")
			(net 1 "GND")
			(pinfunction "S")
			(pintype "passive")
		)
		(pad "3" smd rect
			(at 1.05 0 270)
			(size 0.6 0.6)
			(layers "B.Cu" "B.Mask" "B.Paste")
			(net 507 "HDMI_IN_CD")
			(pinfunction "D")
			(pintype "passive")
		)
	)
)
